(kicad_pcb
	(version 20240108)
	(generator "pcbnew")
	(generator_version "8.0")
	(general
		(thickness 1.62)
		(legacy_teardrops no)
	)
	(paper "A4")
	(title_block
		(title "Jetson Orin Baseboard")
		(date "2025-03-12")
		(rev "1.3.4")
		(company "Antmicro Ltd")
		(comment 1 "www.antmicro.com")
		(comment 9 "footprints 454-458 of 677")
	)
	(layers
		(0 "F.Cu" signal)
		(1 "In1.Cu" signal)
		(2 "In2.Cu" signal)
		(3 "In3.Cu" signal)
		(4 "In4.Cu" jumper)
		(5 "In5.Cu" signal)
		(6 "In6.Cu" signal)
		(31 "B.Cu" signal)
		(32 "B.Adhes" user "B.Adhesive")
		(33 "F.Adhes" user "F.Adhesive")
		(34 "B.Paste" user)
		(35 "F.Paste" user)
		(36 "B.SilkS" user "B.Silkscreen")
		(37 "F.SilkS" user "F.Silkscreen")
		(38 "B.Mask" user)
		(39 "F.Mask" user)
		(40 "Dwgs.User" user "User.Drawings")
		(41 "Cmts.User" user "User.Comments")
		(42 "Eco1.User" user "User.Eco1")
		(43 "Eco2.User" user "User.Eco2")
		(44 "Edge.Cuts" user)
		(45 "Margin" user)
		(46 "B.CrtYd" user "B.Courtyard")
		(47 "F.CrtYd" user "F.Courtyard")
		(48 "B.Fab" user)
		(49 "F.Fab" user)
	)
	(footprint "antmicro-footprints:R_0402_1005Metric"
		(layer "B.Cu")
		(at 106.4 89.82 -90)
		(descr "Resistor SMD 0402")
		(tags "resistor SMD 0402")
		(property "Reference" "R18"
			(at -1.12 0.45 90)
			(layer "B.SilkS")
			(effects
				(font
					(size 0.7 0.7)
					(thickness 0.15)
				)
				(justify left bottom mirror)
			)
		)
		(property "Value" "R_0R_0402"
			(at 0 -1.4 90)
			(layer "B.Fab")
			(effects
				(font
					(size 0.7 0.7)
					(thickness 0.15)
				)
				(justify left bottom mirror)
			)
		)
		(property "Footprint" "antmicro-footprints:R_0402_1005Metric"
			(at 0 0 -90)
			(layer "F.Fab")
			(hide yes)
			(effects
				(font
					(size 1.27 1.27)
					(thickness 0.15)
				)
			)
		)
		(property "Datasheet" "https://industrial.panasonic.com/cdbs/www-data/pdf/RDA0000/AOA0000C301.pdf"
			(at 0 0 -90)
			(layer "F.Fab")
			(hide yes)
			(effects
				(font
					(size 1.27 1.27)
					(thickness 0.15)
				)
			)
		)
		(property "Author" "Antmicro"
			(at 16.58 196.22 0)
			(layer "B.Fab")
			(hide yes)
			(effects
				(font
					(size 1 1)
					(thickness 0.15)
				)
				(justify mirror)
			)
		)
		(property "Current" "1A"
			(at 16.58 196.22 0)
			(layer "B.Fab")
			(hide yes)
			(effects
				(font
					(size 1 1)
					(thickness 0.15)
				)
				(justify mirror)
			)
		)
		(property "License" "Apache-2.0"
			(at 16.58 196.22 0)
			(layer "B.Fab")
			(hide yes)
			(effects
				(font
					(size 1 1)
					(thickness 0.15)
				)
				(justify mirror)
			)
		)
		(property "MPN" "ERJ2GE0R00X"
			(at 16.58 196.22 0)
			(layer "B.Fab")
			(hide yes)
			(effects
				(font
					(size 1 1)
					(thickness 0.15)
				)
				(justify mirror)
			)
		)
		(property "Manufacturer" "Panasonic"
			(at 16.58 196.22 0)
			(layer "B.Fab")
			(hide yes)
			(effects
				(font
					(size 1 1)
					(thickness 0.15)
				)
				(justify mirror)
			)
		)
		(property "Tolerance" ""
			(at 16.58 196.22 0)
			(layer "B.Fab")
			(hide yes)
			(effects
				(font
					(size 1 1)
					(thickness 0.15)
				)
				(justify mirror)
			)
		)
		(property "Val" "0R"
			(at 16.58 196.22 0)
			(layer "B.Fab")
			(hide yes)
			(effects
				(font
					(size 1 1)
					(thickness 0.15)
				)
				(justify mirror)
			)
		)
		(sheetname "M.2")
		(sheetfile "m-2.kicad_sch")
		(attr smd)
		(fp_rect
			(start -0.925 0.47)
			(end 0.925 -0.47)
			(stroke
				(width 0.05)
				(type default)
			)
			(fill none)
			(layer "B.CrtYd")
		)
		(fp_rect
			(start -0.5 0.25)
			(end 0.5 -0.25)
			(stroke
				(width 0.15)
				(type solid)
			)
			(fill none)
			(layer "B.Fab")
		)
		(fp_text user "Author: Antmicro"
			(at -0.95 -4.169 90)
			(layer "B.Fab")
			(hide yes)
			(effects
				(font
					(size 0.7 0.7)
					(thickness 0.15)
				)
				(justify left bottom mirror)
			)
		)
		(fp_text user "${REFERENCE}"
			(at -0.95 -3.168 90)
			(layer "B.Fab")
			(hide yes)
			(effects
				(font
					(size 0.7 0.7)
					(thickness 0.15)
				)
				(justify left bottom mirror)
			)
		)
		(fp_text user "License: Apache-2.0"
			(at -0.95 -5.169 90)
			(layer "B.Fab")
			(hide yes)
			(effects
				(font
					(size 0.7 0.7)
					(thickness 0.15)
				)
				(justify left bottom mirror)
			)
		)
		(pad "1" smd roundrect
			(at -0.48 0 270)
			(size 0.59 0.64)
			(layers "B.Cu" "B.Paste" "B.Mask")
			(roundrect_rratio 0.25)
			(net 455 "PCIE0_RST*")
			(pintype "passive")
		)
		(pad "2" smd roundrect
			(at 0.48 0 270)
			(size 0.59 0.64)
			(layers "B.Cu" "B.Paste" "B.Mask")
			(roundrect_rratio 0.25)
			(net 247 "/M.2/~{M2_M_PERST}")
			(pintype "passive")
		)
	)
	(footprint "antmicro-footprints:R_0402_1005Metric"
		(layer "B.Cu")
		(at 55.075 84.25)
		(descr "Resistor SMD 0402")
		(tags "resistor SMD 0402")
		(property "Reference" "R283"
			(at -1.075 0.65 0)
			(layer "B.SilkS")
			(effects
				(font
					(size 0.7 0.7)
					(thickness 0.15)
				)
				(justify right top mirror)
			)
		)
		(property "Value" "R_560R_0402"
			(at -1.011843 -1.772046 0)
			(layer "B.Fab")
			(effects
				(font
					(size 0.7 0.7)
					(thickness 0.15)
				)
				(justify right top mirror)
			)
		)
		(property "Footprint" "antmicro-footprints:R_0402_1005Metric"
			(at 0 0 0)
			(layer "B.Fab")
			(hide yes)
			(effects
				(font
					(size 1.27 1.27)
					(thickness 0.15)
				)
				(justify mirror)
			)
		)
		(property "Datasheet" "https://www.bourns.com/docs/product-datasheets/cr.pdf"
			(at 0 0 0)
			(layer "B.Fab")
			(hide yes)
			(effects
				(font
					(size 1.27 1.27)
					(thickness 0.15)
				)
				(justify mirror)
			)
		)
		(property "Description" "SMD Chip Resistor, 560 ohm, ± 1%, 100 mW, 0402 [1005 Metric], Thick Film, Precision"
			(at 0 0 0)
			(layer "B.Fab")
			(hide yes)
			(effects
				(font
					(size 1.27 1.27)
					(thickness 0.15)
				)
				(justify mirror)
			)
		)
		(property "MPN" "CR0402-FX-5600GLF"
			(at 0 0 180)
			(unlocked yes)
			(layer "B.Fab")
			(hide yes)
			(effects
				(font
					(size 1 1)
					(thickness 0.15)
				)
				(justify mirror)
			)
		)
		(property "Manufacturer" "Bourns"
			(at 0 0 180)
			(unlocked yes)
			(layer "B.Fab")
			(hide yes)
			(effects
				(font
					(size 1 1)
					(thickness 0.15)
				)
				(justify mirror)
			)
		)
		(property "License" "Apache-2.0"
			(at 0 0 180)
			(unlocked yes)
			(layer "B.Fab")
			(hide yes)
			(effects
				(font
					(size 1 1)
					(thickness 0.15)
				)
				(justify mirror)
			)
		)
		(property "Author" "Antmicro"
			(at 0 0 180)
			(unlocked yes)
			(layer "B.Fab")
			(hide yes)
			(effects
				(font
					(size 1 1)
					(thickness 0.15)
				)
				(justify mirror)
			)
		)
		(property "Val" "560R"
			(at 0 0 180)
			(unlocked yes)
			(layer "B.Fab")
			(hide yes)
			(effects
				(font
					(size 1 1)
					(thickness 0.15)
				)
				(justify mirror)
			)
		)
		(property "Tolerance" "1%"
			(at 0 0 180)
			(unlocked yes)
			(layer "B.Fab")
			(hide yes)
			(effects
				(font
					(size 1 1)
					(thickness 0.15)
				)
				(justify mirror)
			)
		)
		(sheetname "Supply")
		(sheetfile "supply.kicad_sch")
		(attr smd)
		(fp_poly
			(pts
				(xy -0.925 0.47) (xy 0.925 0.47) (xy 0.925 -0.47) (xy -0.925 -0.47)
			)
			(stroke
				(width 0.05)
				(type default)
			)
			(fill none)
			(layer "B.CrtYd")
		)
		(fp_poly
			(pts
				(xy -0.5 0.25) (xy 0.5 0.25) (xy 0.5 -0.25) (xy -0.5 -0.25)
			)
			(stroke
				(width 0.15)
				(type solid)
			)
			(fill none)
			(layer "B.Fab")
		)
		(fp_text user "${REFERENCE}"
			(at -0.95 -3.168 0)
			(layer "B.Fab")
			(hide yes)
			(effects
				(font
					(size 0.7 0.7)
					(thickness 0.15)
				)
				(justify right top mirror)
			)
		)
		(fp_text user "Author: Antmicro"
			(at -0.95 -4.169 0)
			(layer "B.Fab")
			(hide yes)
			(effects
				(font
					(size 0.7 0.7)
					(thickness 0.15)
				)
				(justify right top mirror)
			)
		)
		(fp_text user "License: Apache-2.0"
			(at -0.949999 -5.169 0)
			(layer "B.Fab")
			(hide yes)
			(effects
				(font
					(size 0.7 0.7)
					(thickness 0.15)
				)
				(justify right top mirror)
			)
		)
		(pad "1" smd roundrect
			(at -0.48 0)
			(size 0.59 0.64)
			(layers "B.Cu" "B.Paste" "B.Mask")
			(roundrect_rratio 0.25)
			(net 1 "GND")
			(pintype "passive")
		)
		(pad "2" smd roundrect
			(at 0.48 0)
			(size 0.59 0.64)
			(layers "B.Cu" "B.Paste" "B.Mask")
			(roundrect_rratio 0.25)
			(net 790 "Net-(U29-ILIM)")
			(pintype "passive")
		)
	)
	(footprint "antmicro-footprints:R_0402_1005Metric"
		(layer "B.Cu")
		(at 131.6 93.2 90)
		(descr "Resistor SMD 0402")
		(tags "resistor SMD 0402")
		(property "Reference" "R141"
			(at 3.67 0.45 -90)
			(layer "B.SilkS")
			(effects
				(font
					(size 0.7 0.7)
					(thickness 0.15)
				)
				(justify left bottom mirror)
			)
		)
		(property "Value" "R_0R_0402"
			(at 0 -1.4 -90)
			(layer "B.Fab")
			(effects
				(font
					(size 0.7 0.7)
					(thickness 0.15)
				)
				(justify left bottom mirror)
			)
		)
		(property "Footprint" "antmicro-footprints:R_0402_1005Metric"
			(at 0 0 90)
			(layer "F.Fab")
			(hide yes)
			(effects
				(font
					(size 1.27 1.27)
					(thickness 0.15)
				)
			)
		)
		(property "Datasheet" "https://industrial.panasonic.com/cdbs/www-data/pdf/RDA0000/AOA0000C301.pdf"
			(at 0 0 90)
			(layer "F.Fab")
			(hide yes)
			(effects
				(font
					(size 1.27 1.27)
					(thickness 0.15)
				)
			)
		)
		(property "Author" "Antmicro"
			(at 224.8 -38.4 0)
			(layer "B.Fab")
			(hide yes)
			(effects
				(font
					(size 1 1)
					(thickness 0.15)
				)
				(justify mirror)
			)
		)
		(property "Current" "1A"
			(at 224.8 -38.4 0)
			(layer "B.Fab")
			(hide yes)
			(effects
				(font
					(size 1 1)
					(thickness 0.15)
				)
				(justify mirror)
			)
		)
		(property "License" "Apache-2.0"
			(at 224.8 -38.4 0)
			(layer "B.Fab")
			(hide yes)
			(effects
				(font
					(size 1 1)
					(thickness 0.15)
				)
				(justify mirror)
			)
		)
		(property "MPN" "ERJ2GE0R00X"
			(at 224.8 -38.4 0)
			(layer "B.Fab")
			(hide yes)
			(effects
				(font
					(size 1 1)
					(thickness 0.15)
				)
				(justify mirror)
			)
		)
		(property "Manufacturer" "Panasonic"
			(at 224.8 -38.4 0)
			(layer "B.Fab")
			(hide yes)
			(effects
				(font
					(size 1 1)
					(thickness 0.15)
				)
				(justify mirror)
			)
		)
		(property "Tolerance" ""
			(at 224.8 -38.4 0)
			(layer "B.Fab")
			(hide yes)
			(effects
				(font
					(size 1 1)
					(thickness 0.15)
				)
				(justify mirror)
			)
		)
		(property "Val" "0R"
			(at 224.8 -38.4 0)
			(layer "B.Fab")
			(hide yes)
			(effects
				(font
					(size 1 1)
					(thickness 0.15)
				)
				(justify mirror)
			)
		)
		(sheetname "Peripherals")
		(sheetfile "peripherals.kicad_sch")
		(attr smd exclude_from_pos_files exclude_from_bom dnp)
		(fp_rect
			(start -0.925 0.47)
			(end 0.925 -0.47)
			(stroke
				(width 0.05)
				(type default)
			)
			(fill none)
			(layer "B.CrtYd")
		)
		(fp_rect
			(start -0.5 0.25)
			(end 0.5 -0.25)
			(stroke
				(width 0.15)
				(type solid)
			)
			(fill none)
			(layer "B.Fab")
		)
		(fp_text user "Author: Antmicro"
			(at -0.95 -4.169 -90)
			(layer "B.Fab")
			(hide yes)
			(effects
				(font
					(size 0.7 0.7)
					(thickness 0.15)
				)
				(justify left bottom mirror)
			)
		)
		(fp_text user "License: Apache-2.0"
			(at -0.95 -5.169 -90)
			(layer "B.Fab")
			(hide yes)
			(effects
				(font
					(size 0.7 0.7)
					(thickness 0.15)
				)
				(justify left bottom mirror)
			)
		)
		(fp_text user "${REFERENCE}"
			(at -0.95 -3.168 -90)
			(layer "B.Fab")
			(hide yes)
			(effects
				(font
					(size 0.7 0.7)
					(thickness 0.15)
				)
				(justify left bottom mirror)
			)
		)
		(pad "1" smd roundrect
			(at -0.48 0 90)
			(size 0.59 0.64)
			(layers "B.Cu" "B.Paste" "B.Mask")
			(roundrect_rratio 0.25)
			(net 619 "/Peripherals/USB_CONN_P")
			(pintype "passive")
		)
		(pad "2" smd roundrect
			(at 0.48 0 90)
			(size 0.59 0.64)
			(layers "B.Cu" "B.Paste" "B.Mask")
			(roundrect_rratio 0.25)
			(net 436 "USB1_D_P")
			(pintype "passive")
		)
	)
	(footprint "antmicro-footprints:TP_SMD_0.75mm"
		(layer "B.Cu")
		(at 103.3008 101.55 -90)
		(property "Reference" "TP36"
			(at 0 0.6 90)
			(layer "B.SilkS")
			(hide yes)
			(effects
				(font
					(size 0.7 0.7)
					(thickness 0.15)
				)
				(justify left bottom mirror)
			)
		)
		(property "Value" "TP_0.75mm_SMD"
			(at 0 -1.2 90)
			(layer "B.Fab")
			(effects
				(font
					(size 0.7 0.7)
					(thickness 0.15)
				)
				(justify left bottom mirror)
			)
		)
		(property "Footprint" "antmicro-footprints:TP_SMD_0.75mm"
			(at 0 0 -90)
			(layer "F.Fab")
			(hide yes)
			(effects
				(font
					(size 1.27 1.27)
					(thickness 0.15)
				)
			)
		)
		(property "Author" "Antmicro"
			(at 1.7508 204.8508 0)
			(layer "B.Fab")
			(hide yes)
			(effects
				(font
					(size 1 1)
					(thickness 0.15)
				)
				(justify mirror)
			)
		)
		(property "License" "Apache-2.0"
			(at 1.7508 204.8508 0)
			(layer "B.Fab")
			(hide yes)
			(effects
				(font
					(size 1 1)
					(thickness 0.15)
				)
				(justify mirror)
			)
		)
		(property "MPN" ""
			(at 1.7508 204.8508 0)
			(layer "B.Fab")
			(hide yes)
			(effects
				(font
					(size 1 1)
					(thickness 0.15)
				)
				(justify mirror)
			)
		)
		(property "Manufacturer" ""
			(at 1.7508 204.8508 0)
			(layer "B.Fab")
			(hide yes)
			(effects
				(font
					(size 1 1)
					(thickness 0.15)
				)
				(justify mirror)
			)
		)
		(sheetname "CSI")
		(sheetfile "csi.kicad_sch")
		(attr exclude_from_pos_files exclude_from_bom)
		(fp_circle
			(center 0 0)
			(end 0.475 0)
			(stroke
				(width 0.05)
				(type default)
			)
			(fill none)
			(layer "B.CrtYd")
		)
		(fp_text user "License: Apache-2.0"
			(at -0.4 -5.101 90)
			(layer "B.Fab")
			(hide yes)
			(effects
				(font
					(size 0.7 0.7)
					(thickness 0.15)
				)
				(justify left bottom mirror)
			)
		)
		(fp_text user "${REFERENCE}"
			(at -0.4 -2.7 90)
			(layer "B.Fab")
			(hide yes)
			(effects
				(font
					(size 0.7 0.7)
					(thickness 0.15)
				)
				(justify left bottom mirror)
			)
		)
		(fp_text user "Author: Antmicro"
			(at -0.4 -3.901 90)
			(layer "B.Fab")
			(hide yes)
			(effects
				(font
					(size 0.7 0.7)
					(thickness 0.15)
				)
				(justify left bottom mirror)
			)
		)
		(pad "1" smd circle
			(at 0 0 270)
			(size 0.75 0.75)
			(layers "B.Cu" "B.Mask")
			(net 535 "/CSI/MUX_I2C_4_SDA")
			(pinfunction "1")
			(pintype "passive")
		)
	)
	(footprint "antmicro-footprints:R_Array_4x0201_Panasonic_EXB18V"
		(layer "B.Cu")
		(at 119.53 74.35 -90)
		(property "Reference" "R107"
			(at 0.87 -1.53 90)
			(layer "B.SilkS")
			(effects
				(font
					(size 0.7 0.7)
					(thickness 0.15)
				)
				(justify right bottom mirror)
			)
		)
		(property "Value" "R_4x0R_0201_array"
			(at -1.1 -1.8 90)
			(layer "B.Fab")
			(effects
				(font
					(size 0.7 0.7)
					(thickness 0.15)
				)
				(justify left bottom mirror)
			)
		)
		(property "Footprint" "antmicro-footprints:R_Array_4x0201_Panasonic_EXB18V"
			(at 0 0 -90)
			(layer "F.Fab")
			(hide yes)
			(effects
				(font
					(size 1.27 1.27)
					(thickness 0.15)
				)
			)
		)
		(property "Datasheet" "http://industrial.panasonic.com/cdbs/www-data/pdf/AOC0000/AOC0000C14.pdf"
			(at 0 0 -90)
			(layer "F.Fab")
			(hide yes)
			(effects
				(font
					(size 1.27 1.27)
					(thickness 0.15)
				)
			)
		)
		(property "Author" "Antmicro"
			(at 45.18 193.88 0)
			(layer "B.Fab")
			(hide yes)
			(effects
				(font
					(size 1 1)
					(thickness 0.15)
				)
				(justify mirror)
			)
		)
		(property "License" "Apache-2.0"
			(at 45.18 193.88 0)
			(layer "B.Fab")
			(hide yes)
			(effects
				(font
					(size 1 1)
					(thickness 0.15)
				)
				(justify mirror)
			)
		)
		(property "MPN" "EXB-18VR000X"
			(at 45.18 193.88 0)
			(layer "B.Fab")
			(hide yes)
			(effects
				(font
					(size 1 1)
					(thickness 0.15)
				)
				(justify mirror)
			)
		)
		(property "Manufacturer" "Panasonic"
			(at 45.18 193.88 0)
			(layer "B.Fab")
			(hide yes)
			(effects
				(font
					(size 1 1)
					(thickness 0.15)
				)
				(justify mirror)
			)
		)
		(property "Val" "4x0R_0201"
			(at 45.18 193.88 0)
			(layer "B.Fab")
			(hide yes)
			(effects
				(font
					(size 1 1)
					(thickness 0.15)
				)
				(justify mirror)
			)
		)
		(sheetname "CSI")
		(sheetfile "csi.kicad_sch")
		(attr smd)
		(fp_line
			(start -0.8 -0.45)
			(end -0.8 0.45)
			(stroke
				(width 0.12)
				(type solid)
			)
			(layer "B.SilkS")
		)
		(fp_line
			(start 0.8 -0.45)
			(end 0.8 0.45)
			(stroke
				(width 0.12)
				(type solid)
			)
			(layer "B.SilkS")
		)
		(fp_rect
			(start -0.898 0.66)
			(end 0.898 -0.65)
			(stroke
				(width 0.05)
				(type solid)
			)
			(fill none)
			(layer "B.CrtYd")
		)
		(fp_text user "${REFERENCE}"
			(at -1.051 -3.2 90)
			(layer "B.Fab")
			(hide yes)
			(effects
				(font
					(size 0.7 0.7)
					(thickness 0.15)
				)
				(justify left bottom mirror)
			)
		)
		(fp_text user "Author: Antmicro"
			(at -1.051 -4.599 90)
			(layer "B.Fab")
			(hide yes)
			(effects
				(font
					(size 0.7 0.7)
					(thickness 0.15)
				)
				(justify left bottom mirror)
			)
		)
		(fp_text user "License: Apache-2.0"
			(at -1.051 -6 90)
			(layer "B.Fab")
			(hide yes)
			(effects
				(font
					(size 0.7 0.7)
					(thickness 0.15)
				)
				(justify left bottom mirror)
			)
		)
		(pad "1" smd roundrect
			(at -0.6 -0.298 270)
			(size 0.2 0.4)
			(layers "B.Cu" "B.Paste" "B.Mask")
			(roundrect_rratio 0.25)
			(net 10 "CSI1_D1_N")
			(pinfunction "R1.1")
			(pintype "passive")
		)
		(pad "2" smd roundrect
			(at -0.202 -0.298 270)
			(size 0.2 0.4)
			(layers "B.Cu" "B.Paste" "B.Mask")
			(roundrect_rratio 0.25)
			(net 12 "CSI1_D1_P")
			(pinfunction "R2.1")
			(pintype "passive")
		)
		(pad "3" smd roundrect
			(at 0.2 -0.298 270)
			(size 0.2 0.4)
			(layers "B.Cu" "B.Paste" "B.Mask")
			(roundrect_rratio 0.25)
			(net 2 "CSI1_D0_N")
			(pinfunction "R3.1")
			(pintype "passive")
		)
		(pad "4" smd roundrect
			(at 0.598 -0.298 270)
			(size 0.2 0.4)
			(layers "B.Cu" "B.Paste" "B.Mask")
			(roundrect_rratio 0.25)
			(net 4 "CSI1_D0_P")
			(pinfunction "R4.1")
			(pintype "passive")
		)
		(pad "5" smd roundrect
			(at 0.598 0.3 270)
			(size 0.2 0.4)
			(layers "B.Cu" "B.Paste" "B.Mask")
			(roundrect_rratio 0.25)
			(net 235 "/CSI/CSI1_1_D0_P")
			(pinfunction "R4.2")
			(pintype "passive")
		)
		(pad "6" smd roundrect
			(at 0.2 0.3 270)
			(size 0.2 0.4)
			(layers "B.Cu" "B.Paste" "B.Mask")
			(roundrect_rratio 0.25)
			(net 234 "/CSI/CSI1_1_D0_N")
			(pinfunction "R3.2")
			(pintype "passive")
		)
		(pad "7" smd roundrect
			(at -0.202 0.3 270)
			(size 0.2 0.4)
			(layers "B.Cu" "B.Paste" "B.Mask")
			(roundrect_rratio 0.25)
			(net 237 "/CSI/CSI1_1_D1_P")
			(pinfunction "R2.2")
			(pintype "passive")
		)
		(pad "8" smd roundrect
			(at -0.6 0.3 270)
			(size 0.2 0.4)
			(layers "B.Cu" "B.Paste" "B.Mask")
			(roundrect_rratio 0.25)
			(net 236 "/CSI/CSI1_1_D1_N")
			(pinfunction "R1.2")
			(pintype "passive")
		)
	)
)
